(kicad_pcb
	(version 20260206)
	(generator "pcbnew")
	(generator_version "10.0")
	(general
		(thickness 1.6)
		(legacy_teardrops no)
	)
	(paper "A4")
	(title_block
		(title "Bryce Canyon_F.DPB_16315-1-OCP.brd")
		(comment 1 "Bryce Canyon / footprints 2208-2214 of 2223")
	)
	(layers
		(0 "F.Cu" signal "TOP")
		(4 "In1.Cu" signal "L2GND")
		(6 "In2.Cu" signal "L3")
		(8 "In3.Cu" signal "L4GND")
		(10 "In4.Cu" signal "L5")
		(12 "In5.Cu" signal "L6VCC")
		(14 "In6.Cu" signal "L7VCC")
		(16 "In7.Cu" signal "L8")
		(18 "In8.Cu" signal "L9GND")
		(20 "In9.Cu" signal "L10")
		(22 "In10.Cu" signal "L11GND")
		(2 "B.Cu" signal "BOTTOM")
		(9 "F.Adhes" user "F.Adhesive")
		(11 "B.Adhes" user "B.Adhesive")
		(13 "F.Paste" user "Package Geometry/Pastemask Top")
		(15 "B.Paste" user "Package Geometry/Pastemask Bottom")
		(5 "F.SilkS" user "Ref Des/Silkscreen Top")
		(7 "B.SilkS" user "Ref Des/Silkscreen Bottom")
		(1 "F.Mask" user "Board Geometry/Soldermask Top")
		(3 "B.Mask" user "Board Geometry/Soldermask Bottom")
		(17 "Dwgs.User" user "User.Drawings")
		(19 "Cmts.User" user "User.Comments")
		(21 "Eco1.User" user "User.Eco1")
		(23 "Eco2.User" user "User.Eco2")
		(25 "Edge.Cuts" user "Board Geometry/Outline")
		(27 "Margin" user)
		(31 "F.CrtYd" user "Package Geometry/Place Bound Top")
		(29 "B.CrtYd" user "Package Geometry/Place Bound Bottom")
		(35 "F.Fab" user "Ref Des/Assembly Top")
		(33 "B.Fab" user "Ref Des/Assembly Bottom")
	)
	(footprint ""
		(layer "B.Cu")
		(at 182.512208 -226.19208)
		(property "Reference" "C687"
			(at 0 0 0)
			(layer "B.SilkS")
			(hide yes)
			(effects
				(font
					(size 1.27 1.27)
				)
				(justify mirror)
			)
		)
		(property "Value" "SC1U16V3KX-5GP"
			(at 0 -2.8194 0)
			(unlocked yes)
			(layer "B.Fab")
			(hide yes)
			(effects
				(font
					(size 1.016 1.016)
					(thickness 0.1524)
				)
				(justify mirror)
			)
		)
		(property "Device Type" "C603H36"
			(at 0 -4.3434 0)
			(unlocked yes)
			(layer "B.Fab")
			(hide yes)
			(effects
				(font
					(size 1.016 1.016)
					(thickness 0.1524)
				)
				(justify mirror)
			)
		)
		(duplicate_pad_numbers_are_jumpers no)
		(fp_line
			(start -0.508 0)
			(end 0.508 0)
			(stroke
				(width 0.2032)
				(type default)
			)
			(layer "B.SilkS")
		)
		(fp_rect
			(start 0.5842 1.3335)
			(end -0.5842 -1.3335)
			(stroke
				(width 0)
				(type default)
			)
			(fill no)
			(layer "B.CrtYd")
		)
		(fp_rect
			(start 0.5842 1.3335)
			(end -0.5842 -1.3335)
			(stroke
				(width 0)
				(type default)
			)
			(fill no)
			(layer "B.Fab")
		)
		(pad "1" smd custom
			(at 0 -0.762 180)
			(size 0.2159 0.2159)
			(layers "B.Cu" "B.Mask" "B.Paste")
			(net "GND")
			(options
				(clearance outline)
				(anchor circle)
			)
			(primitives
				(gr_poly
					(pts
						(arc
							(start -0.3302 0.4318)
							(mid -0.402042 0.402042)
							(end -0.4318 0.3302)
						)
						(arc
							(start -0.4318 -0.3302)
							(mid -0.402042 -0.402042)
							(end -0.3302 -0.4318)
						)
						(arc
							(start 0.3302 -0.4318)
							(mid 0.402042 -0.402042)
							(end 0.4318 -0.3302)
						)
						(arc
							(start 0.4318 0.3302)
							(mid 0.402042 0.402042)
							(end 0.3302 0.4318)
						)
					)
					(width 0)
					(fill yes)
				)
			)
		)
		(pad "2" smd custom
			(at 0 0.762 180)
			(size 0.2159 0.2159)
			(layers "B.Cu" "B.Mask" "B.Paste")
			(net "P3V3_STBY_EN_R")
			(options
				(clearance outline)
				(anchor circle)
			)
			(primitives
				(gr_poly
					(pts
						(arc
							(start -0.3302 0.4318)
							(mid -0.402042 0.402042)
							(end -0.4318 0.3302)
						)
						(arc
							(start -0.4318 -0.3302)
							(mid -0.402042 -0.402042)
							(end -0.3302 -0.4318)
						)
						(arc
							(start 0.3302 -0.4318)
							(mid 0.402042 -0.402042)
							(end 0.4318 -0.3302)
						)
						(arc
							(start 0.4318 0.3302)
							(mid 0.402042 0.402042)
							(end 0.3302 0.4318)
						)
					)
					(width 0)
					(fill yes)
				)
			)
		)
	)
	(footprint ""
		(layer "B.Cu")
		(at 183.078628 -232.791508 180)
		(property "Reference" "L9"
			(at 0 0 0)
			(layer "B.SilkS")
			(hide yes)
			(effects
				(font
					(size 1.27 1.27)
				)
				(justify mirror)
			)
		)
		(property "Value" "COIL-4D7UH-33-GP"
			(at 4.699 -4.0132 180)
			(unlocked yes)
			(layer "B.Fab")
			(hide yes)
			(effects
				(font
					(size 1.016 1.016)
					(thickness 0.1524)
				)
				(justify mirror)
			)
		)
		(property "Device Type" "L7066-1830-UH119"
			(at 4.699 -5.5372 180)
			(unlocked yes)
			(layer "B.Fab")
			(hide yes)
			(effects
				(font
					(size 1.016 1.016)
					(thickness 0.1524)
				)
				(justify mirror)
			)
		)
		(duplicate_pad_numbers_are_jumpers no)
		(fp_line
			(start 3.556 4.4958)
			(end 3.556 -4.4958)
			(stroke
				(width 0.1524)
				(type default)
			)
			(layer "B.SilkS")
		)
		(fp_line
			(start 3.556 -4.4958)
			(end -3.556 -4.4958)
			(stroke
				(width 0.1524)
				(type default)
			)
			(layer "B.SilkS")
		)
		(fp_line
			(start -3.556 4.4958)
			(end 3.556 4.4958)
			(stroke
				(width 0.1524)
				(type default)
			)
			(layer "B.SilkS")
		)
		(fp_line
			(start -3.556 -4.4958)
			(end -3.556 4.4958)
			(stroke
				(width 0.1524)
				(type default)
			)
			(layer "B.SilkS")
		)
		(fp_rect
			(start 3.302 3.4798)
			(end -3.302 -3.4798)
			(stroke
				(width 0)
				(type default)
			)
			(fill no)
			(layer "B.CrtYd")
		)
		(fp_poly
			(pts
				(xy 3.81 4.572) (xy 3.81 -4.572) (xy -3.81 -4.572) (xy -3.81 -0.5588) (xy -3.302 -0.5588) (xy -3.302 -3.4798)
				(xy 3.302 -3.4798) (xy 3.302 3.4798) (xy -3.302 3.4798) (xy -3.302 -0.5461) (xy -3.81 -0.5461) (xy -3.81 4.572)
			)
			(stroke
				(width 0)
				(type default)
			)
			(fill no)
			(layer "B.CrtYd")
		)
		(fp_rect
			(start 3.81 4.572)
			(end -3.81 -4.572)
			(stroke
				(width 0)
				(type default)
			)
			(fill no)
			(layer "B.Fab")
		)
		(pad "1" smd rect
			(at 0 -2.779522)
			(size 3.5052 2.921)
			(layers "B.Cu" "B.Mask" "B.Paste")
			(net "P3V3_STBY_SW")
		)
		(pad "2" smd rect
			(at 0 2.779522)
			(size 3.5052 2.921)
			(layers "B.Cu" "B.Mask" "B.Paste")
			(net "P3V3_STBY_A")
		)
	)
	(footprint ""
		(layer "B.Cu")
		(at 22.1234 -246.7864 180)
		(property "Reference" "C599"
			(at 0 0 0)
			(layer "B.SilkS")
			(hide yes)
			(effects
				(font
					(size 1.27 1.27)
				)
				(justify mirror)
			)
		)
		(property "Value" "SC10U16V5KX-7-GP-U"
			(at 0.0762 -6.1214 180)
			(unlocked yes)
			(layer "B.Fab")
			(hide yes)
			(effects
				(font
					(size 1.016 1.016)
					(thickness 0.1524)
				)
				(justify mirror)
			)
		)
		(property "Device Type" "C805H58"
			(at 0.0762 -8.1534 180)
			(unlocked yes)
			(layer "B.Fab")
			(hide yes)
			(effects
				(font
					(size 1.016 1.016)
					(thickness 0.1524)
				)
				(justify mirror)
			)
		)
		(duplicate_pad_numbers_are_jumpers no)
		(fp_line
			(start -0.635 0)
			(end 0.635 0)
			(stroke
				(width 0.508)
				(type default)
			)
			(layer "B.SilkS")
		)
		(fp_rect
			(start 0.9652 1.778)
			(end -0.9652 -1.778)
			(stroke
				(width 0)
				(type default)
			)
			(fill no)
			(layer "B.CrtYd")
		)
		(fp_poly
			(pts
				(xy 0.9652 -1.778) (xy -0.9652 -1.778) (xy -0.9652 1.778) (xy 0.9652 1.778)
			)
			(stroke
				(width 0)
				(type default)
			)
			(fill no)
			(layer "B.Fab")
		)
		(pad "1" smd rect
			(at 0 -0.9652)
			(size 1.397 1.143)
			(layers "B.Cu" "B.Mask" "B.Paste")
			(net "P12V_A_VIN_U20")
		)
		(pad "2" smd rect
			(at 0 0.9652)
			(size 1.397 1.143)
			(layers "B.Cu" "B.Mask" "B.Paste")
			(net "GND")
		)
	)
	(footprint ""
		(layer "B.Cu")
		(at 189.530482 -230.807006)
		(property "Reference" "C674"
			(at 0 0 0)
			(layer "B.SilkS")
			(hide yes)
			(effects
				(font
					(size 1.27 1.27)
				)
				(justify mirror)
			)
		)
		(property "Value" "SC1U25V3KX-GP"
			(at 0 -2.8194 0)
			(unlocked yes)
			(layer "B.Fab")
			(hide yes)
			(effects
				(font
					(size 1.016 1.016)
					(thickness 0.1524)
				)
				(justify mirror)
			)
		)
		(property "Device Type" "C603H36"
			(at 0 -4.3434 0)
			(unlocked yes)
			(layer "B.Fab")
			(hide yes)
			(effects
				(font
					(size 1.016 1.016)
					(thickness 0.1524)
				)
				(justify mirror)
			)
		)
		(duplicate_pad_numbers_are_jumpers no)
		(fp_line
			(start -0.508 0)
			(end 0.508 0)
			(stroke
				(width 0.2032)
				(type default)
			)
			(layer "B.SilkS")
		)
		(fp_rect
			(start 0.5842 1.3335)
			(end -0.5842 -1.3335)
			(stroke
				(width 0)
				(type default)
			)
			(fill no)
			(layer "B.CrtYd")
		)
		(fp_rect
			(start 0.5842 1.3335)
			(end -0.5842 -1.3335)
			(stroke
				(width 0)
				(type default)
			)
			(fill no)
			(layer "B.Fab")
		)
		(pad "1" smd custom
			(at 0 -0.762 180)
			(size 0.2159 0.2159)
			(layers "B.Cu" "B.Mask" "B.Paste")
			(net "P3V3_STBY_SW")
			(options
				(clearance outline)
				(anchor circle)
			)
			(primitives
				(gr_poly
					(pts
						(arc
							(start -0.3302 0.4318)
							(mid -0.402042 0.402042)
							(end -0.4318 0.3302)
						)
						(arc
							(start -0.4318 -0.3302)
							(mid -0.402042 -0.402042)
							(end -0.3302 -0.4318)
						)
						(arc
							(start 0.3302 -0.4318)
							(mid 0.402042 -0.402042)
							(end 0.4318 -0.3302)
						)
						(arc
							(start 0.4318 0.3302)
							(mid 0.402042 0.402042)
							(end 0.3302 0.4318)
						)
					)
					(width 0)
					(fill yes)
				)
			)
		)
		(pad "2" smd custom
			(at 0 0.762 180)
			(size 0.2159 0.2159)
			(layers "B.Cu" "B.Mask" "B.Paste")
			(net "P3V3_STBY_VBST_RR")
			(options
				(clearance outline)
				(anchor circle)
			)
			(primitives
				(gr_poly
					(pts
						(arc
							(start -0.3302 0.4318)
							(mid -0.402042 0.402042)
							(end -0.4318 0.3302)
						)
						(arc
							(start -0.4318 -0.3302)
							(mid -0.402042 -0.402042)
							(end -0.3302 -0.4318)
						)
						(arc
							(start 0.3302 -0.4318)
							(mid 0.402042 -0.402042)
							(end 0.4318 -0.3302)
						)
						(arc
							(start 0.4318 0.3302)
							(mid 0.402042 0.402042)
							(end 0.3302 0.4318)
						)
					)
					(width 0)
					(fill yes)
				)
			)
		)
	)
	(footprint ""
		(layer "B.Cu")
		(at 267.66012 -106.966766 -90)
		(property "Reference" "TC21"
			(at 0 0 90)
			(layer "B.SilkS")
			(hide yes)
			(effects
				(font
					(size 1.27 1.27)
				)
				(justify mirror)
			)
		)
		(property "Value" "ST100U16VDM-3-GP"
			(at 0 -9.6012 270)
			(unlocked yes)
			(layer "B.Fab")
			(hide yes)
			(effects
				(font
					(size 1.016 1.016)
					(thickness 0.1524)
				)
				(justify mirror)
			)
		)
		(property "Device Type" "CT7343H79"
			(at 0 -11.1252 270)
			(unlocked yes)
			(layer "B.Fab")
			(hide yes)
			(effects
				(font
					(size 1.016 1.016)
					(thickness 0.1524)
				)
				(justify mirror)
			)
		)
		(duplicate_pad_numbers_are_jumpers no)
		(fp_line
			(start -2.286 4.8768)
			(end 2.286 4.8768)
			(stroke
				(width 0.1524)
				(type default)
			)
			(layer "B.SilkS")
		)
		(fp_line
			(start 2.286 4.8768)
			(end 2.286 2.032)
			(stroke
				(width 0.1524)
				(type default)
			)
			(layer "B.SilkS")
		)
		(fp_line
			(start -2.286 2.032)
			(end -2.286 4.8768)
			(stroke
				(width 0.1524)
				(type default)
			)
			(layer "B.SilkS")
		)
		(fp_line
			(start -2.286 -2.032)
			(end -2.286 -4.8768)
			(stroke
				(width 0.1524)
				(type default)
			)
			(layer "B.SilkS")
		)
		(fp_line
			(start -2.1082 -4.699)
			(end 2.1082 -4.699)
			(stroke
				(width 0.508)
				(type default)
			)
			(layer "B.SilkS")
		)
		(fp_line
			(start -2.286 -4.8768)
			(end 2.286 -4.8768)
			(stroke
				(width 0.1524)
				(type default)
			)
			(layer "B.SilkS")
		)
		(fp_line
			(start 2.286 -4.8768)
			(end 2.286 -2.032)
			(stroke
				(width 0.1524)
				(type default)
			)
			(layer "B.SilkS")
		)
		(fp_rect
			(start 2.1463 3.6449)
			(end -2.1463 -3.6449)
			(stroke
				(width 0)
				(type default)
			)
			(fill no)
			(layer "B.CrtYd")
		)
		(fp_poly
			(pts
				(xy 2.54 4.953) (xy 2.54 4.2926) (xy 3.81 4.2926) (xy 3.81 -4.2926) (xy 2.54 -4.2926) (xy 2.54 -4.953)
				(xy -2.54 -4.953) (xy -2.54 -4.2926) (xy -3.81 -4.2926) (xy -3.81 -1.6256) (xy -2.1463 -1.6256)
				(xy -2.1463 -3.6449) (xy 2.1463 -3.6449) (xy 2.1463 3.6449) (xy -2.1463 3.6449) (xy -2.1463 -1.6129)
				(xy -3.81 -1.6129) (xy -3.81 4.2926) (xy -2.54 4.2926) (xy -2.54 4.953)
			)
			(stroke
				(width 0)
				(type default)
			)
			(fill no)
			(layer "B.CrtYd")
		)
		(fp_rect
			(start 2.54 4.953)
			(end -2.54 -4.953)
			(stroke
				(width 0)
				(type default)
			)
			(fill no)
			(layer "B.Fab")
		)
		(fp_rect
			(start -2.54 4.2926)
			(end -3.81 -4.2926)
			(stroke
				(width 0)
				(type default)
			)
			(fill no)
			(layer "B.Fab")
		)
		(fp_rect
			(start 3.81 4.2926)
			(end 2.54 -4.2926)
			(stroke
				(width 0)
				(type default)
			)
			(fill no)
			(layer "B.Fab")
		)
		(pad "1" smd rect
			(at 0 -3.1496 90)
			(size 2.413 2.286)
			(layers "B.Cu" "B.Mask" "B.Paste")
			(net "P12V_B_COMP")
		)
		(pad "2" smd rect
			(at 0 3.1496 90)
			(size 2.413 2.286)
			(layers "B.Cu" "B.Mask" "B.Paste")
			(net "GND")
		)
		(zone
			(layer "B.Cu")
			(hatch none 0.5)
			(connect_pads
				(clearance 0)
			)
			(min_thickness 0.25)
			(keepout
				(tracks allowed)
				(vias not_allowed)
				(pads allowed)
				(copperpour not_allowed)
				(footprints allowed)
			)
			(placement
				(enabled no)
				(sheetname "")
			)
			(fill
				(thermal_gap 0.5)
				(thermal_bridge_width 0.5)
				(island_removal_mode 0)
			)
			(polygon
				(pts
					(xy 263.06272 -105.455466) (xy 263.06272 -108.478066) (xy 265.95832 -108.478066) (xy 266.28852 -108.478066)
					(xy 266.28852 -105.455466) (xy 265.95832 -105.455466)
				)
			)
		)
		(zone
			(layer "B.Cu")
			(hatch none 0.5)
			(connect_pads
				(clearance 0)
			)
			(min_thickness 0.25)
			(keepout
				(tracks allowed)
				(vias not_allowed)
				(pads allowed)
				(copperpour not_allowed)
				(footprints allowed)
			)
			(placement
				(enabled no)
				(sheetname "")
			)
			(fill
				(thermal_gap 0.5)
				(thermal_bridge_width 0.5)
				(island_removal_mode 0)
			)
			(polygon
				(pts
					(xy 269.34922 -108.478066) (xy 272.25752 -108.478066) (xy 272.25752 -105.455466) (xy 269.36192 -105.455466)
					(xy 269.03172 -105.455466) (xy 269.03172 -108.478066)
				)
			)
		)
	)
	(footprint ""
		(layer "B.Cu")
		(at 474.091 -239.395 90)
		(property "Reference" "C650"
			(at 0 0 90)
			(layer "B.SilkS")
			(hide yes)
			(effects
				(font
					(size 1.27 1.27)
				)
				(justify mirror)
			)
		)
		(property "Value" "SC10U16V5KX-7-GP-U"
			(at 0.0762 -6.1214 90)
			(unlocked yes)
			(layer "B.Fab")
			(hide yes)
			(effects
				(font
					(size 1.016 1.016)
					(thickness 0.1524)
				)
				(justify mirror)
			)
		)
		(property "Device Type" "C805H58"
			(at 0.0762 -8.1534 90)
			(unlocked yes)
			(layer "B.Fab")
			(hide yes)
			(effects
				(font
					(size 1.016 1.016)
					(thickness 0.1524)
				)
				(justify mirror)
			)
		)
		(duplicate_pad_numbers_are_jumpers no)
		(fp_line
			(start -0.635 0)
			(end 0.635 0)
			(stroke
				(width 0.508)
				(type default)
			)
			(layer "B.SilkS")
		)
		(fp_rect
			(start 0.9652 1.778)
			(end -0.9652 -1.778)
			(stroke
				(width 0)
				(type default)
			)
			(fill no)
			(layer "B.CrtYd")
		)
		(fp_poly
			(pts
				(xy 0.9652 -1.778) (xy -0.9652 -1.778) (xy -0.9652 1.778) (xy 0.9652 1.778)
			)
			(stroke
				(width 0)
				(type default)
			)
			(fill no)
			(layer "B.Fab")
		)
		(pad "1" smd rect
			(at 0 -0.9652 270)
			(size 1.397 1.143)
			(layers "B.Cu" "B.Mask" "B.Paste")
			(net "P12V_A_VIN_U27")
		)
		(pad "2" smd rect
			(at 0 0.9652 270)
			(size 1.397 1.143)
			(layers "B.Cu" "B.Mask" "B.Paste")
			(net "GND")
		)
	)
	(footprint ""
		(layer "B.Cu")
		(at 176.431702 -154.24277)
		(property "Reference" "D37"
			(at 0 0 0)
			(layer "B.SilkS")
			(hide yes)
			(effects
				(font
					(size 1.27 1.27)
				)
				(justify mirror)
			)
		)
		(property "Value" "SMCJ14A-13-F-GP"
			(at 4.445 1.1684 0)
			(unlocked yes)
			(layer "B.Fab")
			(hide yes)
			(effects
				(font
					(size 1.016 1.016)
					(thickness 0.1524)
				)
				(justify mirror)
			)
		)
		(property "Device Type" "D795930AKH104"
			(at 4.445 -0.3556 0)
			(unlocked yes)
			(layer "B.Fab")
			(hide yes)
			(effects
				(font
					(size 1.016 1.016)
					(thickness 0.1524)
				)
				(justify mirror)
			)
		)
		(duplicate_pad_numbers_are_jumpers no)
		(fp_line
			(start -3.2004 -4.8641)
			(end 3.2004 -4.8641)
			(stroke
				(width 0.1524)
				(type default)
			)
			(layer "B.SilkS")
		)
		(fp_line
			(start -3.2004 4.8641)
			(end -3.2004 -4.8641)
			(stroke
				(width 0.1524)
				(type default)
			)
			(layer "B.SilkS")
		)
		(fp_line
			(start -3.2004 5.0419)
			(end 3.2004 5.0419)
			(stroke
				(width 0.508)
				(type default)
			)
			(layer "B.SilkS")
		)
		(fp_line
			(start 3.2004 -4.8641)
			(end 3.2004 4.8641)
			(stroke
				(width 0.1524)
				(type default)
			)
			(layer "B.SilkS")
		)
		(fp_line
			(start 3.2004 4.8641)
			(end -3.2004 4.8641)
			(stroke
				(width 0.1524)
				(type default)
			)
			(layer "B.SilkS")
		)
		(fp_poly
			(pts
				(xy 2.9464 3.429) (xy 1.4859 3.429) (xy 1.4859 3.9751) (xy -1.4859 3.9751) (xy -1.4859 3.429) (xy -2.9464 3.429)
				(xy -2.9464 -3.429) (xy -1.4859 -3.429) (xy -1.4859 -3.9751) (xy 1.4859 -3.9751) (xy 1.4859 -3.429)
				(xy 2.9464 -3.429)
			)
			(stroke
				(width 0)
				(type default)
			)
			(fill no)
			(layer "B.CrtYd")
		)
		(fp_poly
			(pts
				(xy 3.4544 4.9403) (xy 3.4544 -4.9403) (xy -3.4544 -4.9403) (xy -3.4544 -3.429) (xy -1.4859 -3.429)
				(xy -1.4859 -3.9751) (xy 1.4859 -3.9751) (xy 1.4859 -3.429) (xy 2.9464 -3.429) (xy 2.9464 3.429)
				(xy 1.4859 3.429) (xy 1.4859 3.9751) (xy -1.4859 3.9751) (xy -1.4859 3.429) (xy -2.9464 3.429) (xy -2.9464 -3.4163)
				(xy -3.4544 -3.4163) (xy -3.4544 4.9403)
			)
			(stroke
				(width 0)
				(type default)
			)
			(fill no)
			(layer "B.CrtYd")
		)
		(fp_rect
			(start 3.4544 4.9403)
			(end -3.4544 -4.9403)
			(stroke
				(width 0)
				(type default)
			)
			(fill no)
			(layer "B.Fab")
		)
		(pad "A" smd rect
			(at 0 -3.592068 180)
			(size 3.2258 2.032)
			(layers "B.Cu" "B.Mask" "B.Paste")
			(net "GND")
		)
		(pad "K" smd rect
			(at 0 3.592068 180)
			(size 3.2258 2.032)
			(layers "B.Cu" "B.Mask" "B.Paste")
			(net "P12V_A")
		)
	)
)
